# SCM (Grand Teton) — schematic netlist excerpt (pin names and nets, part order shuffled) for the footprints in the layout excerpt that follows; sources: Cadence DE-HDL packaged netlist, KiCad conversion of 12092022_DA0F0TMDCD0_F0T_Management_Board_D_brd_V3_OCP.brd

R347  Q_RES  120 1% CHIP  pkg 0402LF  page 20 : A = GND ; B = M_BMC_DDR4_MBA1
C276  Q_CAP  0.1UF 25V 10% X7R  pkg 0402  page 49 : A = P3V3_AUX ; B = GND

(kicad_pcb
	(version 20260206)
	(generator "pcbnew")
	(generator_version "10.0")
	(general
		(thickness 1.6)
		(legacy_teardrops no)
	)
	(paper "A4")
	(title_block
		(title "12092022_DA0F0TMDCD0_F0T_Management_Board_D_brd_V3_OCP.brd")
		(comment 1 "Grand Teton / footprints 73-74 of 1440")
	)
	(layers
		(0 "F.Cu" signal "TOP")
		(4 "In1.Cu" signal "GND")
		(6 "In2.Cu" signal "IN1")
		(8 "In3.Cu" signal "GND1")
		(10 "In4.Cu" signal "IN2")
		(12 "In5.Cu" signal "VCC")
		(14 "In6.Cu" signal "VCC1")
		(16 "In7.Cu" signal "IN3")
		(18 "In8.Cu" signal "GND2")
		(20 "In9.Cu" signal "IN4")
		(22 "In10.Cu" signal "GND3")
		(2 "B.Cu" signal "BOTTOM")
		(9 "F.Adhes" user "F.Adhesive")
		(11 "B.Adhes" user "B.Adhesive")
		(13 "F.Paste" user "Package Geometry/Pastemask Top")
		(15 "B.Paste" user "Package Geometry/Pastemask Bottom")
		(5 "F.SilkS" user "Ref Des/Silkscreen Top")
		(7 "B.SilkS" user "Ref Des/Silkscreen Bottom")
		(1 "F.Mask" user "Board Geometry/Soldermask Top")
		(3 "B.Mask" user "Board Geometry/Soldermask Bottom")
		(17 "Dwgs.User" user "User.Drawings")
		(19 "Cmts.User" user "User.Comments")
		(21 "Eco1.User" user "User.Eco1")
		(23 "Eco2.User" user "User.Eco2")
		(25 "Edge.Cuts" user "Board Geometry/Outline")
		(27 "Margin" user)
		(31 "F.CrtYd" user "Package Geometry/Place Bound Top")
		(29 "B.CrtYd" user "Package Geometry/Place Bound Bottom")
		(35 "F.Fab" user "Ref Des/Assembly Top")
		(33 "B.Fab" user "Ref Des/Assembly Bottom")
	)
	(footprint ""
		(layer "F.Cu")
		(at 32.512 -13.7922)
		(property "Reference" "C276"
			(at 0 0 0)
			(layer "F.SilkS")
			(hide yes)
			(effects
				(font
					(size 1.27 1.27)
				)
			)
		)
		(property "Value" ""
			(at 0 0 0)
			(layer "F.Fab")
			(effects
				(font
					(size 1.27 1.27)
				)
			)
		)
		(duplicate_pad_numbers_are_jumpers no)
		(fp_line
			(start -0.7874 -0.4064)
			(end 0.7874 -0.4064)
			(stroke
				(width 0.1524)
				(type default)
			)
			(layer "F.SilkS")
		)
		(fp_line
			(start -0.7874 0.4064)
			(end -0.7874 -0.4064)
			(stroke
				(width 0.1524)
				(type default)
			)
			(layer "F.SilkS")
		)
		(fp_line
			(start 0.7874 -0.4064)
			(end 0.7874 0.4064)
			(stroke
				(width 0.1524)
				(type default)
			)
			(layer "F.SilkS")
		)
		(fp_line
			(start 0.7874 0.4064)
			(end -0.7874 0.4064)
			(stroke
				(width 0.1524)
				(type default)
			)
			(layer "F.SilkS")
		)
		(fp_line
			(start -0.67945 -0.305054)
			(end -0.12065 -0.305054)
			(stroke
				(width 0.1)
				(type default)
			)
			(layer "F.Fab")
		)
		(fp_line
			(start -0.67945 0.3048)
			(end -0.67945 -0.305054)
			(stroke
				(width 0.1)
				(type default)
			)
			(layer "F.Fab")
		)
		(fp_line
			(start -0.12065 -0.305054)
			(end -0.12065 -0.2794)
			(stroke
				(width 0.1)
				(type default)
			)
			(layer "F.Fab")
		)
		(fp_line
			(start -0.12065 -0.2794)
			(end 0.12065 -0.2794)
			(stroke
				(width 0.1)
				(type default)
			)
			(layer "F.Fab")
		)
		(fp_line
			(start -0.12065 0.2794)
			(end -0.12065 0.3048)
			(stroke
				(width 0.1)
				(type default)
			)
			(layer "F.Fab")
		)
		(fp_line
			(start -0.12065 0.3048)
			(end -0.67945 0.3048)
			(stroke
				(width 0.1)
				(type default)
			)
			(layer "F.Fab")
		)
		(fp_line
			(start 0.120396 0.2794)
			(end -0.12065 0.2794)
			(stroke
				(width 0.1)
				(type default)
			)
			(layer "F.Fab")
		)
		(fp_line
			(start 0.120396 0.3048)
			(end 0.120396 0.2794)
			(stroke
				(width 0.1)
				(type default)
			)
			(layer "F.Fab")
		)
		(fp_line
			(start 0.12065 -0.3048)
			(end 0.67945 -0.3048)
			(stroke
				(width 0.1)
				(type default)
			)
			(layer "F.Fab")
		)
		(fp_line
			(start 0.12065 -0.2794)
			(end 0.12065 -0.3048)
			(stroke
				(width 0.1)
				(type default)
			)
			(layer "F.Fab")
		)
		(fp_line
			(start 0.67945 -0.3048)
			(end 0.67945 0.3048)
			(stroke
				(width 0.1)
				(type default)
			)
			(layer "F.Fab")
		)
		(fp_line
			(start 0.67945 0.3048)
			(end 0.120396 0.3048)
			(stroke
				(width 0.1)
				(type default)
			)
			(layer "F.Fab")
		)
		(pad "1" smd circle
			(at -0.40005 0)
			(size 0 0)
			(layers "F.Cu" "F.Mask" "F.Paste")
			(net "P3V3_AUX")
		)
		(pad "2" smd circle
			(at 0.40005 0)
			(size 0 0)
			(layers "F.Cu" "F.Mask" "F.Paste")
			(net "GND")
		)
	)
	(footprint ""
		(layer "F.Cu")
		(at 85.29955 -46.717204 180)
		(property "Reference" "R347"
			(at 0 0 180)
			(layer "F.SilkS")
			(hide yes)
			(effects
				(font
					(size 1.27 1.27)
				)
			)
		)
		(property "Value" ""
			(at 0 0 180)
			(layer "F.Fab")
			(effects
				(font
					(size 1.27 1.27)
				)
			)
		)
		(duplicate_pad_numbers_are_jumpers no)
		(fp_line
			(start 0.7874 0.4064)
			(end -0.7874 0.4064)
			(stroke
				(width 0.1524)
				(type default)
			)
			(layer "F.SilkS")
		)
		(fp_line
			(start 0.7874 -0.4064)
			(end 0.7874 0.4064)
			(stroke
				(width 0.1524)
				(type default)
			)
			(layer "F.SilkS")
		)
		(fp_line
			(start -0.7874 0.4064)
			(end -0.7874 -0.4064)
			(stroke
				(width 0.1524)
				(type default)
			)
			(layer "F.SilkS")
		)
		(fp_line
			(start -0.7874 -0.4064)
			(end 0.7874 -0.4064)
			(stroke
				(width 0.1524)
				(type default)
			)
			(layer "F.SilkS")
		)
		(fp_line
			(start 0.67945 0.3048)
			(end 0.120396 0.3048)
			(stroke
				(width 0.1)
				(type default)
			)
			(layer "F.Fab")
		)
		(fp_line
			(start 0.67945 -0.3048)
			(end 0.67945 0.3048)
			(stroke
				(width 0.1)
				(type default)
			)
			(layer "F.Fab")
		)
		(fp_line
			(start 0.12065 -0.2794)
			(end 0.12065 -0.3048)
			(stroke
				(width 0.1)
				(type default)
			)
			(layer "F.Fab")
		)
		(fp_line
			(start 0.12065 -0.3048)
			(end 0.67945 -0.3048)
			(stroke
				(width 0.1)
				(type default)
			)
			(layer "F.Fab")
		)
		(fp_line
			(start 0.120396 0.3048)
			(end 0.120396 0.2794)
			(stroke
				(width 0.1)
				(type default)
			)
			(layer "F.Fab")
		)
		(fp_line
			(start 0.120396 0.2794)
			(end -0.12065 0.2794)
			(stroke
				(width 0.1)
				(type default)
			)
			(layer "F.Fab")
		)
		(fp_line
			(start -0.12065 0.3048)
			(end -0.67945 0.3048)
			(stroke
				(width 0.1)
				(type default)
			)
			(layer "F.Fab")
		)
		(fp_line
			(start -0.12065 0.2794)
			(end -0.12065 0.3048)
			(stroke
				(width 0.1)
				(type default)
			)
			(layer "F.Fab")
		)
		(fp_line
			(start -0.12065 -0.2794)
			(end 0.12065 -0.2794)
			(stroke
				(width 0.1)
				(type default)
			)
			(layer "F.Fab")
		)
		(fp_line
			(start -0.12065 -0.305054)
			(end -0.12065 -0.2794)
			(stroke
				(width 0.1)
				(type default)
			)
			(layer "F.Fab")
		)
		(fp_line
			(start -0.67945 0.3048)
			(end -0.67945 -0.305054)
			(stroke
				(width 0.1)
				(type default)
			)
			(layer "F.Fab")
		)
		(fp_line
			(start -0.67945 -0.305054)
			(end -0.12065 -0.305054)
			(stroke
				(width 0.1)
				(type default)
			)
			(layer "F.Fab")
		)
		(pad "1" smd circle
			(at -0.40005 0 180)
			(size 0 0)
			(layers "F.Cu" "F.Mask" "F.Paste")
			(net "GND")
		)
		(pad "2" smd circle
			(at 0.40005 0 180)
			(size 0 0)
			(layers "F.Cu" "F.Mask" "F.Paste")
			(net "M_BMC_DDR4_MBA1")
		)
	)
)
